# S9S_MB_2U (Grand Teton) — schematic netlist excerpt (pin names and nets, part order shuffled) for the footprints in the layout excerpt that follows; sources: Cadence DE-HDL packaged netlist, KiCad conversion of 03242023_DA0F0TMBIJ0_F0T_Motherboard_J_brd_V01_OCP.brd

PR1400  Q_RES  49.9 1% CHIP  pkg 0402LF  page 296 : A = P12V_AUX_CPU1_DIMM_ISEN_P ; B = PVCCD_HV_CPU1_ISENSE_P
PR667  Q_RES  10K 1% EMPTY  pkg 0402LF  page 292 : A = PVCCFA_EHV_CPU1_BTSEN ; B = GND

(kicad_pcb
	(version 20260206)
	(generator "pcbnew")
	(generator_version "10.0")
	(general
		(thickness 1.6)
		(legacy_teardrops no)
	)
	(paper "A4")
	(title_block
		(title "03242023_DA0F0TMBIJ0_F0T_Motherboard_J_brd_V01_OCP.brd")
		(comment 1 "Grand Teton / footprints 5317-5318 of 6105")
	)
	(layers
		(0 "F.Cu" signal "TOP")
		(4 "In1.Cu" signal "GND")
		(6 "In2.Cu" signal "IN1")
		(8 "In3.Cu" signal "GND1")
		(10 "In4.Cu" signal "IN2")
		(12 "In5.Cu" signal "GND2")
		(14 "In6.Cu" signal "IN3")
		(16 "In7.Cu" signal "GND3")
		(18 "In8.Cu" signal "VCC")
		(20 "In9.Cu" signal "VCC1")
		(22 "In10.Cu" signal "GND4")
		(24 "In11.Cu" signal "IN4")
		(26 "In12.Cu" signal "GND5")
		(28 "In13.Cu" signal "IN5")
		(30 "In14.Cu" signal "GND6")
		(32 "In15.Cu" signal "IN6")
		(34 "In16.Cu" signal "GND7")
		(2 "B.Cu" signal "BOTTOM")
		(9 "F.Adhes" user "F.Adhesive")
		(11 "B.Adhes" user "B.Adhesive")
		(13 "F.Paste" user "Package Geometry/Pastemask Top")
		(15 "B.Paste" user "Package Geometry/Pastemask Bottom")
		(5 "F.SilkS" user "Ref Des/Silkscreen Top")
		(7 "B.SilkS" user "Ref Des/Silkscreen Bottom")
		(1 "F.Mask" user "Board Geometry/Soldermask Top")
		(3 "B.Mask" user "Board Geometry/Soldermask Bottom")
		(17 "Dwgs.User" user "User.Drawings")
		(19 "Cmts.User" user "User.Comments")
		(21 "Eco1.User" user "User.Eco1")
		(23 "Eco2.User" user "User.Eco2")
		(25 "Edge.Cuts" user "Board Geometry/Outline")
		(27 "Margin" user)
		(31 "F.CrtYd" user "Package Geometry/Place Bound Top")
		(29 "B.CrtYd" user "Package Geometry/Place Bound Bottom")
		(35 "F.Fab" user "Ref Des/Assembly Top")
		(33 "B.Fab" user "Ref Des/Assembly Bottom")
	)
	(footprint ""
		(layer "B.Cu")
		(at 34.846514 -165.841426)
		(property "Reference" "PR1400"
			(at 0 0 0)
			(layer "B.SilkS")
			(hide yes)
			(effects
				(font
					(size 1.27 1.27)
				)
				(justify mirror)
			)
		)
		(property "Value" ""
			(at 0 0 0)
			(layer "B.Fab")
			(effects
				(font
					(size 1.27 1.27)
				)
				(justify mirror)
			)
		)
		(duplicate_pad_numbers_are_jumpers no)
		(fp_line
			(start -0.7874 -0.4064)
			(end -0.7874 0.4064)
			(stroke
				(width 0.1524)
				(type default)
			)
			(layer "B.SilkS")
		)
		(fp_line
			(start -0.7874 0.4064)
			(end 0.7874 0.4064)
			(stroke
				(width 0.1524)
				(type default)
			)
			(layer "B.SilkS")
		)
		(fp_line
			(start 0.7874 -0.4064)
			(end -0.7874 -0.4064)
			(stroke
				(width 0.1524)
				(type default)
			)
			(layer "B.SilkS")
		)
		(fp_line
			(start 0.7874 0.4064)
			(end 0.7874 -0.4064)
			(stroke
				(width 0.1524)
				(type default)
			)
			(layer "B.SilkS")
		)
		(fp_line
			(start -0.67945 -0.3048)
			(end -0.67945 0.3048)
			(stroke
				(width 0.1)
				(type default)
			)
			(layer "B.Fab")
		)
		(fp_line
			(start -0.67945 0.3048)
			(end -0.120396 0.3048)
			(stroke
				(width 0.1)
				(type default)
			)
			(layer "B.Fab")
		)
		(fp_line
			(start -0.12065 -0.3048)
			(end -0.67945 -0.3048)
			(stroke
				(width 0.1)
				(type default)
			)
			(layer "B.Fab")
		)
		(fp_line
			(start -0.12065 -0.2794)
			(end -0.12065 -0.3048)
			(stroke
				(width 0.1)
				(type default)
			)
			(layer "B.Fab")
		)
		(fp_line
			(start -0.120396 0.2794)
			(end 0.12065 0.2794)
			(stroke
				(width 0.1)
				(type default)
			)
			(layer "B.Fab")
		)
		(fp_line
			(start -0.120396 0.3048)
			(end -0.120396 0.2794)
			(stroke
				(width 0.1)
				(type default)
			)
			(layer "B.Fab")
		)
		(fp_line
			(start 0.12065 -0.305054)
			(end 0.12065 -0.2794)
			(stroke
				(width 0.1)
				(type default)
			)
			(layer "B.Fab")
		)
		(fp_line
			(start 0.12065 -0.2794)
			(end -0.12065 -0.2794)
			(stroke
				(width 0.1)
				(type default)
			)
			(layer "B.Fab")
		)
		(fp_line
			(start 0.12065 0.2794)
			(end 0.12065 0.3048)
			(stroke
				(width 0.1)
				(type default)
			)
			(layer "B.Fab")
		)
		(fp_line
			(start 0.12065 0.3048)
			(end 0.67945 0.3048)
			(stroke
				(width 0.1)
				(type default)
			)
			(layer "B.Fab")
		)
		(fp_line
			(start 0.67945 -0.305054)
			(end 0.12065 -0.305054)
			(stroke
				(width 0.1)
				(type default)
			)
			(layer "B.Fab")
		)
		(fp_line
			(start 0.67945 0.3048)
			(end 0.67945 -0.305054)
			(stroke
				(width 0.1)
				(type default)
			)
			(layer "B.Fab")
		)
		(pad "1" smd circle
			(at 0.40005 0 180)
			(size 0 0)
			(layers "B.Cu" "B.Mask" "B.Paste")
			(net "P12V_AUX_CPU1_DIMM_ISEN_P")
		)
		(pad "2" smd circle
			(at -0.40005 0 180)
			(size 0 0)
			(layers "B.Cu" "B.Mask" "B.Paste")
			(net "PVCCD_HV_CPU1_ISENSE_P")
		)
	)
	(footprint ""
		(layer "B.Cu")
		(at 28.574238 -130.877056 -90)
		(property "Reference" "PR667"
			(at 0 0 90)
			(layer "B.SilkS")
			(hide yes)
			(effects
				(font
					(size 1.27 1.27)
				)
				(justify mirror)
			)
		)
		(property "Value" ""
			(at 0 0 90)
			(layer "B.Fab")
			(effects
				(font
					(size 1.27 1.27)
				)
				(justify mirror)
			)
		)
		(duplicate_pad_numbers_are_jumpers no)
		(fp_line
			(start -0.7874 0.4064)
			(end 0.7874 0.4064)
			(stroke
				(width 0.1524)
				(type default)
			)
			(layer "B.SilkS")
		)
		(fp_line
			(start 0.7874 0.4064)
			(end 0.7874 -0.4064)
			(stroke
				(width 0.1524)
				(type default)
			)
			(layer "B.SilkS")
		)
		(fp_line
			(start -0.7874 -0.4064)
			(end -0.7874 0.4064)
			(stroke
				(width 0.1524)
				(type default)
			)
			(layer "B.SilkS")
		)
		(fp_line
			(start 0.7874 -0.4064)
			(end -0.7874 -0.4064)
			(stroke
				(width 0.1524)
				(type default)
			)
			(layer "B.SilkS")
		)
		(fp_line
			(start -0.67945 0.3048)
			(end -0.120396 0.3048)
			(stroke
				(width 0.1)
				(type default)
			)
			(layer "B.Fab")
		)
		(fp_line
			(start -0.120396 0.3048)
			(end -0.120396 0.2794)
			(stroke
				(width 0.1)
				(type default)
			)
			(layer "B.Fab")
		)
		(fp_line
			(start 0.12065 0.3048)
			(end 0.67945 0.3048)
			(stroke
				(width 0.1)
				(type default)
			)
			(layer "B.Fab")
		)
		(fp_line
			(start 0.67945 0.3048)
			(end 0.67945 -0.305054)
			(stroke
				(width 0.1)
				(type default)
			)
			(layer "B.Fab")
		)
		(fp_line
			(start -0.120396 0.2794)
			(end 0.12065 0.2794)
			(stroke
				(width 0.1)
				(type default)
			)
			(layer "B.Fab")
		)
		(fp_line
			(start 0.12065 0.2794)
			(end 0.12065 0.3048)
			(stroke
				(width 0.1)
				(type default)
			)
			(layer "B.Fab")
		)
		(fp_line
			(start -0.12065 -0.2794)
			(end -0.12065 -0.3048)
			(stroke
				(width 0.1)
				(type default)
			)
			(layer "B.Fab")
		)
		(fp_line
			(start 0.12065 -0.2794)
			(end -0.12065 -0.2794)
			(stroke
				(width 0.1)
				(type default)
			)
			(layer "B.Fab")
		)
		(fp_line
			(start -0.67945 -0.3048)
			(end -0.67945 0.3048)
			(stroke
				(width 0.1)
				(type default)
			)
			(layer "B.Fab")
		)
		(fp_line
			(start -0.12065 -0.3048)
			(end -0.67945 -0.3048)
			(stroke
				(width 0.1)
				(type default)
			)
			(layer "B.Fab")
		)
		(fp_line
			(start 0.12065 -0.305054)
			(end 0.12065 -0.2794)
			(stroke
				(width 0.1)
				(type default)
			)
			(layer "B.Fab")
		)
		(fp_line
			(start 0.67945 -0.305054)
			(end 0.12065 -0.305054)
			(stroke
				(width 0.1)
				(type default)
			)
			(layer "B.Fab")
		)
		(pad "1" smd circle
			(at 0.40005 0 90)
			(size 0 0)
			(layers "B.Cu" "B.Mask" "B.Paste")
			(net "PVCCFA_EHV_CPU1_BTSEN")
		)
		(pad "2" smd circle
			(at -0.40005 0 90)
			(size 0 0)
			(layers "B.Cu" "B.Mask" "B.Paste")
			(net "GND")
		)
	)
)
